# T6G (Grand Teton) — schematic netlist excerpt (pin names and nets, part order shuffled) for the footprints in the layout excerpt that follows; sources: Cadence DE-HDL packaged netlist, KiCad conversion of 04192023_DAF0TMB3IC0_F0TG_MB_C_brd_V02_OCP.brd

R4555  Q_RES  4.7K 5% EMPTY  pkg 0402LF  page 124 : A = SWB_HSC_EN_BUF_R ; B = GND
R8300  Q_RES  1K 1% CHIP  pkg 0402LF  page 193 : A = P3V3_AUX ; B = PWRGD_PVDDCR_CPU0_P0_R
C1072  Q_CAP  0.1UF 10V 10% X7S  pkg C0201  page 186 : A = P3V3_AUX ; B = GND

(kicad_pcb
	(version 20260206)
	(generator "pcbnew")
	(generator_version "10.0")
	(general
		(thickness 1.6)
		(legacy_teardrops no)
	)
	(paper "A4")
	(title_block
		(title "04192023_DAF0TMB3IC0_F0TG_MB_C_brd_V02_OCP.brd")
		(comment 1 "Grand Teton / footprints 2189-2191 of 8354")
	)
	(layers
		(0 "F.Cu" signal "TOP")
		(4 "In1.Cu" signal "GND")
		(6 "In2.Cu" signal "IN1")
		(8 "In3.Cu" signal "GND1")
		(10 "In4.Cu" signal "IN2")
		(12 "In5.Cu" signal "GND2")
		(14 "In6.Cu" signal "IN3")
		(16 "In7.Cu" signal "GND3")
		(18 "In8.Cu" signal "VCC")
		(20 "In9.Cu" signal "VCC1")
		(22 "In10.Cu" signal "GND4")
		(24 "In11.Cu" signal "IN4")
		(26 "In12.Cu" signal "GND5")
		(28 "In13.Cu" signal "IN5")
		(30 "In14.Cu" signal "GND6")
		(32 "In15.Cu" signal "IN6")
		(34 "In16.Cu" signal "GND7")
		(2 "B.Cu" signal "BOTTOM")
		(9 "F.Adhes" user "F.Adhesive")
		(11 "B.Adhes" user "B.Adhesive")
		(13 "F.Paste" user "Package Geometry/Pastemask Top")
		(15 "B.Paste" user "Package Geometry/Pastemask Bottom")
		(5 "F.SilkS" user "Ref Des/Silkscreen Top")
		(7 "B.SilkS" user "Ref Des/Silkscreen Bottom")
		(1 "F.Mask" user "Board Geometry/Soldermask Top")
		(3 "B.Mask" user "Board Geometry/Soldermask Bottom")
		(17 "Dwgs.User" user "User.Drawings")
		(19 "Cmts.User" user "User.Comments")
		(21 "Eco1.User" user "User.Eco1")
		(23 "Eco2.User" user "User.Eco2")
		(25 "Edge.Cuts" user "Board Geometry/Outline")
		(27 "Margin" user)
		(31 "F.CrtYd" user "Package Geometry/Place Bound Top")
		(29 "B.CrtYd" user "Package Geometry/Place Bound Bottom")
		(35 "F.Fab" user "Ref Des/Assembly Top")
		(33 "B.Fab" user "Ref Des/Assembly Bottom")
	)
	(footprint ""
		(layer "F.Cu")
		(at 372.937278 -138.424158)
		(property "Reference" "R8300"
			(at 0 0 0)
			(layer "F.SilkS")
			(hide yes)
			(effects
				(font
					(size 1.27 1.27)
				)
			)
		)
		(property "Value" ""
			(at 0 0 0)
			(layer "F.Fab")
			(effects
				(font
					(size 1.27 1.27)
				)
			)
		)
		(duplicate_pad_numbers_are_jumpers no)
		(fp_line
			(start -0.7874 -0.4064)
			(end 0.7874 -0.4064)
			(stroke
				(width 0.1524)
				(type default)
			)
			(layer "F.SilkS")
		)
		(fp_line
			(start -0.7874 0.4064)
			(end -0.7874 -0.4064)
			(stroke
				(width 0.1524)
				(type default)
			)
			(layer "F.SilkS")
		)
		(fp_line
			(start 0.7874 -0.4064)
			(end 0.7874 0.4064)
			(stroke
				(width 0.1524)
				(type default)
			)
			(layer "F.SilkS")
		)
		(fp_line
			(start 0.7874 0.4064)
			(end -0.7874 0.4064)
			(stroke
				(width 0.1524)
				(type default)
			)
			(layer "F.SilkS")
		)
		(fp_line
			(start -0.67945 -0.305054)
			(end -0.12065 -0.305054)
			(stroke
				(width 0.1)
				(type default)
			)
			(layer "F.Fab")
		)
		(fp_line
			(start -0.67945 0.3048)
			(end -0.67945 -0.305054)
			(stroke
				(width 0.1)
				(type default)
			)
			(layer "F.Fab")
		)
		(fp_line
			(start -0.12065 -0.305054)
			(end -0.12065 -0.2794)
			(stroke
				(width 0.1)
				(type default)
			)
			(layer "F.Fab")
		)
		(fp_line
			(start -0.12065 -0.2794)
			(end 0.12065 -0.2794)
			(stroke
				(width 0.1)
				(type default)
			)
			(layer "F.Fab")
		)
		(fp_line
			(start -0.12065 0.2794)
			(end -0.12065 0.3048)
			(stroke
				(width 0.1)
				(type default)
			)
			(layer "F.Fab")
		)
		(fp_line
			(start -0.12065 0.3048)
			(end -0.67945 0.3048)
			(stroke
				(width 0.1)
				(type default)
			)
			(layer "F.Fab")
		)
		(fp_line
			(start 0.120396 0.2794)
			(end -0.12065 0.2794)
			(stroke
				(width 0.1)
				(type default)
			)
			(layer "F.Fab")
		)
		(fp_line
			(start 0.120396 0.3048)
			(end 0.120396 0.2794)
			(stroke
				(width 0.1)
				(type default)
			)
			(layer "F.Fab")
		)
		(fp_line
			(start 0.12065 -0.3048)
			(end 0.67945 -0.3048)
			(stroke
				(width 0.1)
				(type default)
			)
			(layer "F.Fab")
		)
		(fp_line
			(start 0.12065 -0.2794)
			(end 0.12065 -0.3048)
			(stroke
				(width 0.1)
				(type default)
			)
			(layer "F.Fab")
		)
		(fp_line
			(start 0.67945 -0.3048)
			(end 0.67945 0.3048)
			(stroke
				(width 0.1)
				(type default)
			)
			(layer "F.Fab")
		)
		(fp_line
			(start 0.67945 0.3048)
			(end 0.120396 0.3048)
			(stroke
				(width 0.1)
				(type default)
			)
			(layer "F.Fab")
		)
		(pad "1" smd circle
			(at -0.40005 0)
			(size 0 0)
			(layers "F.Cu" "F.Mask" "F.Paste")
			(net "P3V3_AUX")
		)
		(pad "2" smd circle
			(at 0.40005 0)
			(size 0 0)
			(layers "F.Cu" "F.Mask" "F.Paste")
			(net "PWRGD_PVDDCR_CPU0_P0_R")
		)
	)
	(footprint ""
		(layer "F.Cu")
		(at 288.87928 -394.985748 -90)
		(property "Reference" "C1072"
			(at 0 0 270)
			(layer "F.SilkS")
			(hide yes)
			(effects
				(font
					(size 1.27 1.27)
				)
			)
		)
		(property "Value" ""
			(at 0 0 270)
			(layer "F.Fab")
			(effects
				(font
					(size 1.27 1.27)
				)
			)
		)
		(duplicate_pad_numbers_are_jumpers no)
		(fp_line
			(start -0.299974 0.150114)
			(end -0.299974 -0.150114)
			(stroke
				(width 0.1)
				(type default)
			)
			(layer "F.Fab")
		)
		(fp_line
			(start 0.299974 0.150114)
			(end -0.299974 0.150114)
			(stroke
				(width 0.1)
				(type default)
			)
			(layer "F.Fab")
		)
		(fp_line
			(start -0.299974 -0.150114)
			(end 0.299974 -0.150114)
			(stroke
				(width 0.1)
				(type default)
			)
			(layer "F.Fab")
		)
		(fp_line
			(start 0.299974 -0.150114)
			(end 0.299974 0.150114)
			(stroke
				(width 0.1)
				(type default)
			)
			(layer "F.Fab")
		)
		(pad "1" smd rect
			(at -0.2667 0 270)
			(size 0.3048 0.381)
			(layers "F.Cu" "F.Mask" "F.Paste")
			(net "P3V3_AUX")
		)
		(pad "2" smd rect
			(at 0.2667 0 270)
			(size 0.3048 0.381)
			(layers "F.Cu" "F.Mask" "F.Paste")
			(net "GND")
		)
	)
	(footprint ""
		(layer "F.Cu")
		(at 352.05543 -433.841652 180)
		(property "Reference" "R4555"
			(at 0 0 180)
			(layer "F.SilkS")
			(hide yes)
			(effects
				(font
					(size 1.27 1.27)
				)
			)
		)
		(property "Value" ""
			(at 0 0 180)
			(layer "F.Fab")
			(effects
				(font
					(size 1.27 1.27)
				)
			)
		)
		(duplicate_pad_numbers_are_jumpers no)
		(fp_line
			(start 0.7874 0.4064)
			(end -0.7874 0.4064)
			(stroke
				(width 0.1524)
				(type default)
			)
			(layer "F.SilkS")
		)
		(fp_line
			(start 0.7874 -0.4064)
			(end 0.7874 0.4064)
			(stroke
				(width 0.1524)
				(type default)
			)
			(layer "F.SilkS")
		)
		(fp_line
			(start -0.7874 0.4064)
			(end -0.7874 -0.4064)
			(stroke
				(width 0.1524)
				(type default)
			)
			(layer "F.SilkS")
		)
		(fp_line
			(start -0.7874 -0.4064)
			(end 0.7874 -0.4064)
			(stroke
				(width 0.1524)
				(type default)
			)
			(layer "F.SilkS")
		)
		(fp_line
			(start 0.67945 0.3048)
			(end 0.120396 0.3048)
			(stroke
				(width 0.1)
				(type default)
			)
			(layer "F.Fab")
		)
		(fp_line
			(start 0.67945 -0.3048)
			(end 0.67945 0.3048)
			(stroke
				(width 0.1)
				(type default)
			)
			(layer "F.Fab")
		)
		(fp_line
			(start 0.12065 -0.2794)
			(end 0.12065 -0.3048)
			(stroke
				(width 0.1)
				(type default)
			)
			(layer "F.Fab")
		)
		(fp_line
			(start 0.12065 -0.3048)
			(end 0.67945 -0.3048)
			(stroke
				(width 0.1)
				(type default)
			)
			(layer "F.Fab")
		)
		(fp_line
			(start 0.120396 0.3048)
			(end 0.120396 0.2794)
			(stroke
				(width 0.1)
				(type default)
			)
			(layer "F.Fab")
		)
		(fp_line
			(start 0.120396 0.2794)
			(end -0.12065 0.2794)
			(stroke
				(width 0.1)
				(type default)
			)
			(layer "F.Fab")
		)
		(fp_line
			(start -0.12065 0.3048)
			(end -0.67945 0.3048)
			(stroke
				(width 0.1)
				(type default)
			)
			(layer "F.Fab")
		)
		(fp_line
			(start -0.12065 0.2794)
			(end -0.12065 0.3048)
			(stroke
				(width 0.1)
				(type default)
			)
			(layer "F.Fab")
		)
		(fp_line
			(start -0.12065 -0.2794)
			(end 0.12065 -0.2794)
			(stroke
				(width 0.1)
				(type default)
			)
			(layer "F.Fab")
		)
		(fp_line
			(start -0.12065 -0.305054)
			(end -0.12065 -0.2794)
			(stroke
				(width 0.1)
				(type default)
			)
			(layer "F.Fab")
		)
		(fp_line
			(start -0.67945 0.3048)
			(end -0.67945 -0.305054)
			(stroke
				(width 0.1)
				(type default)
			)
			(layer "F.Fab")
		)
		(fp_line
			(start -0.67945 -0.305054)
			(end -0.12065 -0.305054)
			(stroke
				(width 0.1)
				(type default)
			)
			(layer "F.Fab")
		)
		(pad "1" smd circle
			(at -0.40005 0 180)
			(size 0 0)
			(layers "F.Cu" "F.Mask" "F.Paste")
			(net "SWB_HSC_EN_BUF_R")
		)
		(pad "2" smd circle
			(at 0.40005 0 180)
			(size 0 0)
			(layers "F.Cu" "F.Mask" "F.Paste")
			(net "GND")
		)
	)
)
